(kicad_pcb
	(version 20260206)
	(generator "pcbnew")
	(generator_version "10.0")
	(general
		(thickness 1.6)
		(legacy_teardrops no)
	)
	(paper "A4")
	(title_block
		(title "baseboard — 13948-1b.1110WZS1818.brd")
		(comment 1 "Honey Badger (Wiwynn) / footprints 384-390 of 2523")
	)
	(layers
		(0 "F.Cu" signal "TOP")
		(4 "In1.Cu" signal "L2GND")
		(6 "In2.Cu" signal "L3")
		(8 "In3.Cu" signal "L4VCC")
		(10 "In4.Cu" signal "L5VCC")
		(12 "In5.Cu" signal "L6")
		(14 "In6.Cu" signal "L7GND")
		(2 "B.Cu" signal "BOTTOM")
		(9 "F.Adhes" user "F.Adhesive")
		(11 "B.Adhes" user "B.Adhesive")
		(13 "F.Paste" user "Package Geometry/Pastemask Top")
		(15 "B.Paste" user "Package Geometry/Pastemask Bottom")
		(5 "F.SilkS" user "Ref Des/Silkscreen Top")
		(7 "B.SilkS" user "Ref Des/Silkscreen Bottom")
		(1 "F.Mask" user "Board Geometry/Soldermask Top")
		(3 "B.Mask" user "Board Geometry/Soldermask Bottom")
		(17 "Dwgs.User" user "User.Drawings")
		(19 "Cmts.User" user "User.Comments")
		(21 "Eco1.User" user "User.Eco1")
		(23 "Eco2.User" user "User.Eco2")
		(25 "Edge.Cuts" user "Board Geometry/Outline")
		(27 "Margin" user)
		(31 "F.CrtYd" user "Package Geometry/Place Bound Top")
		(29 "B.CrtYd" user "Package Geometry/Place Bound Bottom")
		(35 "F.Fab" user "Ref Des/Assembly Top")
		(33 "B.Fab" user "Ref Des/Assembly Bottom")
	)
	(footprint ""
		(layer "F.Cu")
		(at 95.89897 -90.805 90)
		(property "Reference" "SR796"
			(at 0 0 90)
			(layer "F.SilkS")
			(hide yes)
			(effects
				(font
					(size 1.27 1.27)
				)
			)
		)
		(property "Value" "4K75R2F-1-GP"
			(at 0.064008 -3.993896 90)
			(unlocked yes)
			(layer "F.Fab")
			(hide yes)
			(effects
				(font
					(size 1.016 1.016)
					(thickness 0.1524)
				)
			)
		)
		(property "Device Type" "R402H16"
			(at 0.064008 -5.517896 90)
			(unlocked yes)
			(layer "F.Fab")
			(hide yes)
			(effects
				(font
					(size 1.016 1.016)
					(thickness 0.1524)
				)
			)
		)
		(duplicate_pad_numbers_are_jumpers no)
		(fp_line
			(start 0.508 -0.9398)
			(end -0.508 -0.9398)
			(stroke
				(width 0.1524)
				(type default)
			)
			(layer "F.SilkS")
		)
		(fp_line
			(start -0.508 -0.9398)
			(end -0.508 0.9398)
			(stroke
				(width 0.1524)
				(type default)
			)
			(layer "F.SilkS")
		)
		(fp_rect
			(start -0.508 0.9398)
			(end 0.508 -0.9398)
			(stroke
				(width 0)
				(type default)
			)
			(fill no)
			(layer "F.CrtYd")
		)
		(fp_rect
			(start -0.508 0.9398)
			(end 0.508 -0.9398)
			(stroke
				(width 0)
				(type default)
			)
			(fill no)
			(layer "F.Fab")
		)
		(pad "1" smd custom
			(at 0 -0.4445 90)
			(size 0.1397 0.1397)
			(layers "F.Cu" "F.Mask" "F.Paste")
			(net "P1V8_E")
			(options
				(clearance outline)
				(anchor circle)
			)
			(primitives
				(gr_poly
					(pts
						(arc
							(start -0.1778 -0.2794)
							(mid -0.249642 -0.249642)
							(end -0.2794 -0.1778)
						)
						(arc
							(start -0.2794 0.1778)
							(mid -0.249642 0.249642)
							(end -0.1778 0.2794)
						)
						(arc
							(start 0.1778 0.2794)
							(mid 0.249642 0.249642)
							(end 0.2794 0.1778)
						)
						(arc
							(start 0.2794 -0.1778)
							(mid 0.249642 -0.249642)
							(end 0.1778 -0.2794)
						)
					)
					(width 0)
					(fill yes)
				)
			)
		)
		(pad "2" smd custom
			(at 0 0.4445 90)
			(size 0.1397 0.1397)
			(layers "F.Cu" "F.Mask" "F.Paste")
			(net "EXP_CLK_SEL0")
			(options
				(clearance outline)
				(anchor circle)
			)
			(primitives
				(gr_poly
					(pts
						(arc
							(start -0.1778 -0.2794)
							(mid -0.249642 -0.249642)
							(end -0.2794 -0.1778)
						)
						(arc
							(start -0.2794 0.1778)
							(mid -0.249642 0.249642)
							(end -0.1778 0.2794)
						)
						(arc
							(start 0.1778 0.2794)
							(mid 0.249642 0.249642)
							(end 0.2794 0.1778)
						)
						(arc
							(start 0.2794 -0.1778)
							(mid 0.249642 -0.249642)
							(end 0.1778 -0.2794)
						)
					)
					(width 0)
					(fill yes)
				)
			)
		)
	)
	(footprint ""
		(layer "F.Cu")
		(at 221.733872 -180.285136 -90)
		(property "Reference" "R497"
			(at 0 0 270)
			(layer "F.SilkS")
			(hide yes)
			(effects
				(font
					(size 1.27 1.27)
				)
			)
		)
		(property "Value" "200R3F-GP"
			(at -0.0254 -2.5146 270)
			(unlocked yes)
			(layer "F.Fab")
			(hide yes)
			(effects
				(font
					(size 1.016 1.016)
					(thickness 0.1524)
				)
			)
		)
		(property "Device Type" "R603H22"
			(at -0.0254 -4.0386 270)
			(unlocked yes)
			(layer "F.Fab")
			(hide yes)
			(effects
				(font
					(size 1.016 1.016)
					(thickness 0.1524)
				)
			)
		)
		(duplicate_pad_numbers_are_jumpers no)
		(fp_line
			(start -0.4826 0)
			(end -0.2032 0)
			(stroke
				(width 0.2032)
				(type default)
			)
			(layer "F.SilkS")
		)
		(fp_line
			(start 0.2032 0)
			(end 0.4826 0)
			(stroke
				(width 0.2032)
				(type default)
			)
			(layer "F.SilkS")
		)
		(fp_rect
			(start -0.5842 1.3335)
			(end 0.5842 -1.3335)
			(stroke
				(width 0)
				(type default)
			)
			(fill no)
			(layer "F.CrtYd")
		)
		(fp_rect
			(start -0.5842 1.3335)
			(end 0.5842 -1.3335)
			(stroke
				(width 0)
				(type default)
			)
			(fill no)
			(layer "F.Fab")
		)
		(pad "1" smd custom
			(at 0 -0.762 270)
			(size 0.2159 0.2159)
			(layers "F.Cu" "F.Mask" "F.Paste")
			(net "P3V3_STBY")
			(options
				(clearance outline)
				(anchor circle)
			)
			(primitives
				(gr_poly
					(pts
						(arc
							(start -0.3302 -0.4318)
							(mid -0.402042 -0.402042)
							(end -0.4318 -0.3302)
						)
						(arc
							(start -0.4318 0.3302)
							(mid -0.402042 0.402042)
							(end -0.3302 0.4318)
						)
						(arc
							(start 0.3302 0.4318)
							(mid 0.402042 0.402042)
							(end 0.4318 0.3302)
						)
						(arc
							(start 0.4318 -0.3302)
							(mid 0.402042 -0.402042)
							(end 0.3302 -0.4318)
						)
					)
					(width 0)
					(fill yes)
				)
			)
		)
		(pad "2" smd custom
			(at 0 0.762 270)
			(size 0.2159 0.2159)
			(layers "F.Cu" "F.Mask" "F.Paste")
			(net "HB_A_OUT_EXP")
			(options
				(clearance outline)
				(anchor circle)
			)
			(primitives
				(gr_poly
					(pts
						(arc
							(start -0.3302 -0.4318)
							(mid -0.402042 -0.402042)
							(end -0.4318 -0.3302)
						)
						(arc
							(start -0.4318 0.3302)
							(mid -0.402042 0.402042)
							(end -0.3302 0.4318)
						)
						(arc
							(start 0.3302 0.4318)
							(mid 0.402042 0.402042)
							(end 0.4318 0.3302)
						)
						(arc
							(start 0.4318 -0.3302)
							(mid 0.402042 -0.402042)
							(end 0.3302 -0.4318)
						)
					)
					(width 0)
					(fill yes)
				)
			)
		)
	)
	(footprint ""
		(layer "F.Cu")
		(at 176.012348 -115.687856 -90)
		(property "Reference" "PC188"
			(at 0 0 270)
			(layer "F.SilkS")
			(hide yes)
			(effects
				(font
					(size 1.27 1.27)
				)
			)
		)
		(property "Value" "SC470P50V2KX-3GP"
			(at 1.1811 -2.7051 270)
			(unlocked yes)
			(layer "F.Fab")
			(hide yes)
			(effects
				(font
					(size 1.016 1.016)
					(thickness 0.1524)
				)
			)
		)
		(property "Device Type" "C402H22"
			(at 1.1811 -4.2291 270)
			(unlocked yes)
			(layer "F.Fab")
			(hide yes)
			(effects
				(font
					(size 1.016 1.016)
					(thickness 0.1524)
				)
			)
		)
		(duplicate_pad_numbers_are_jumpers no)
		(fp_rect
			(start -0.4318 0.9525)
			(end 0.4318 -0.9525)
			(stroke
				(width 0)
				(type default)
			)
			(fill no)
			(layer "F.CrtYd")
		)
		(fp_rect
			(start -0.4318 0.9525)
			(end 0.4318 -0.9525)
			(stroke
				(width 0)
				(type default)
			)
			(fill no)
			(layer "F.Fab")
		)
		(pad "1" smd custom
			(at 0 -0.4445 270)
			(size 0.1524 0.1524)
			(layers "F.Cu" "F.Mask" "F.Paste")
			(net "P0V9_E_SNB")
			(options
				(clearance outline)
				(anchor circle)
			)
			(primitives
				(gr_poly
					(pts
						(arc
							(start 0.3048 -0.2032)
							(mid 0.275042 -0.275042)
							(end 0.2032 -0.3048)
						)
						(arc
							(start -0.2032 -0.3048)
							(mid -0.275042 -0.275042)
							(end -0.3048 -0.2032)
						)
						(arc
							(start -0.3048 0.2032)
							(mid -0.275042 0.275042)
							(end -0.2032 0.3048)
						)
						(arc
							(start 0.2032 0.3048)
							(mid 0.275042 0.275042)
							(end 0.3048 0.2032)
						)
					)
					(width 0)
					(fill yes)
				)
			)
		)
		(pad "2" smd custom
			(at 0 0.4445 270)
			(size 0.1524 0.1524)
			(layers "F.Cu" "F.Mask" "F.Paste")
			(net "GND")
			(options
				(clearance outline)
				(anchor circle)
			)
			(primitives
				(gr_poly
					(pts
						(arc
							(start 0.3048 -0.2032)
							(mid 0.275042 -0.275042)
							(end 0.2032 -0.3048)
						)
						(arc
							(start -0.2032 -0.3048)
							(mid -0.275042 -0.275042)
							(end -0.3048 -0.2032)
						)
						(arc
							(start -0.3048 0.2032)
							(mid -0.275042 0.275042)
							(end -0.2032 0.3048)
						)
						(arc
							(start 0.2032 0.3048)
							(mid 0.275042 0.275042)
							(end 0.3048 0.2032)
						)
					)
					(width 0)
					(fill yes)
				)
			)
		)
	)
	(footprint ""
		(layer "F.Cu")
		(at 34.544 -214.122 -90)
		(property "Reference" "SU74"
			(at 0 0 270)
			(layer "F.SilkS")
			(hide yes)
			(effects
				(font
					(size 1.27 1.27)
				)
			)
		)
		(property "Value" "PCA9306DCTT-GP"
			(at 0 -11.6332 270)
			(unlocked yes)
			(layer "F.Fab")
			(hide yes)
			(effects
				(font
					(size 1.016 1.016)
					(thickness 0.1524)
				)
			)
		)
		(property "Device Type" "SSOIC8H52"
			(at 0 -13.1572 270)
			(unlocked yes)
			(layer "F.Fab")
			(hide yes)
			(effects
				(font
					(size 1.016 1.016)
					(thickness 0.1524)
				)
			)
		)
		(duplicate_pad_numbers_are_jumpers no)
		(fp_line
			(start -1.524 0.5842)
			(end -1.524 2.286)
			(stroke
				(width 0.508)
				(type default)
			)
			(layer "F.SilkS")
		)
		(fp_line
			(start 1.0668 0.5842)
			(end -1.524 0.5842)
			(stroke
				(width 0.1524)
				(type default)
			)
			(layer "F.SilkS")
		)
		(fp_line
			(start -1.397 0)
			(end -1.7018 0.3048)
			(stroke
				(width 0.1524)
				(type default)
			)
			(layer "F.SilkS")
		)
		(fp_line
			(start -1.397 0)
			(end -1.7018 -0.3048)
			(stroke
				(width 0.1524)
				(type default)
			)
			(layer "F.SilkS")
		)
		(fp_line
			(start -1.7018 -0.5842)
			(end -1.7018 2.286)
			(stroke
				(width 0.1524)
				(type default)
			)
			(layer "F.SilkS")
		)
		(fp_line
			(start -1.7018 -0.5842)
			(end 1.0668 -0.5842)
			(stroke
				(width 0.1524)
				(type default)
			)
			(layer "F.SilkS")
		)
		(fp_line
			(start 1.0668 -0.5842)
			(end 1.0668 0.5842)
			(stroke
				(width 0.1524)
				(type default)
			)
			(layer "F.SilkS")
		)
		(fp_poly
			(pts
				(xy -1.1684 -0.5842) (xy 1.0668 -0.5842) (xy 1.0668 0.5842) (xy -1.1684 0.5842)
			)
			(stroke
				(width 0)
				(type default)
			)
			(fill yes)
			(layer "F.SilkS")
		)
		(fp_poly
			(pts
				(xy -1.778 2.54) (xy 1.778 2.54) (xy 1.778 -2.54) (xy -1.778 -2.54)
			)
			(stroke
				(width 0)
				(type default)
			)
			(fill no)
			(layer "F.CrtYd")
		)
		(fp_poly
			(pts
				(xy -1.778 -2.54) (xy 1.778 -2.54) (xy 1.778 2.54) (xy -1.778 2.54)
			)
			(stroke
				(width 0)
				(type default)
			)
			(fill no)
			(layer "F.Fab")
		)
		(pad "1" smd rect
			(at -0.97536 1.6256 270)
			(size 0.3556 1.524)
			(layers "F.Cu" "F.Mask" "F.Paste")
			(net "GND")
		)
		(pad "2" smd rect
			(at -0.32512 1.6256 270)
			(size 0.3556 1.524)
			(layers "F.Cu" "F.Mask" "F.Paste")
			(net "P1V8_E")
		)
		(pad "3" smd rect
			(at 0.32512 1.6256 270)
			(size 0.3556 1.524)
			(layers "F.Cu" "F.Mask" "F.Paste")
			(net "EXP_SCL_0")
		)
		(pad "4" smd rect
			(at 0.97536 1.6256 270)
			(size 0.3556 1.524)
			(layers "F.Cu" "F.Mask" "F.Paste")
			(net "EXP_SDA_0")
		)
		(pad "5" smd rect
			(at 0.97536 -1.6256 270)
			(size 0.3556 1.524)
			(layers "F.Cu" "F.Mask" "F.Paste")
			(net "EXP_SDA_L_0")
		)
		(pad "6" smd rect
			(at 0.32512 -1.6256 270)
			(size 0.3556 1.524)
			(layers "F.Cu" "F.Mask" "F.Paste")
			(net "EXP_SCL_L_0")
		)
		(pad "7" smd rect
			(at -0.32512 -1.6256 270)
			(size 0.3556 1.524)
			(layers "F.Cu" "F.Mask" "F.Paste")
			(net "EXP_I2C_VREF_4")
		)
		(pad "8" smd rect
			(at -0.97536 -1.6256 270)
			(size 0.3556 1.524)
			(layers "F.Cu" "F.Mask" "F.Paste")
			(net "EXP_I2C_VREF_4")
		)
	)
	(footprint ""
		(layer "F.Cu")
		(at 311.15 -114.935 90)
		(property "Reference" "PR27"
			(at 0 0 90)
			(layer "F.SilkS")
			(hide yes)
			(effects
				(font
					(size 1.27 1.27)
				)
			)
		)
		(property "Value" "10R3F-GP"
			(at -0.0254 -2.5146 90)
			(unlocked yes)
			(layer "F.Fab")
			(hide yes)
			(effects
				(font
					(size 1.016 1.016)
					(thickness 0.1524)
				)
			)
		)
		(property "Device Type" "R603H22"
			(at -0.0254 -4.0386 90)
			(unlocked yes)
			(layer "F.Fab")
			(hide yes)
			(effects
				(font
					(size 1.016 1.016)
					(thickness 0.1524)
				)
			)
		)
		(duplicate_pad_numbers_are_jumpers no)
		(fp_line
			(start 0.2032 0)
			(end 0.4826 0)
			(stroke
				(width 0.2032)
				(type default)
			)
			(layer "F.SilkS")
		)
		(fp_line
			(start -0.4826 0)
			(end -0.2032 0)
			(stroke
				(width 0.2032)
				(type default)
			)
			(layer "F.SilkS")
		)
		(fp_rect
			(start -0.5842 1.3335)
			(end 0.5842 -1.3335)
			(stroke
				(width 0)
				(type default)
			)
			(fill no)
			(layer "F.CrtYd")
		)
		(fp_rect
			(start -0.5842 1.3335)
			(end 0.5842 -1.3335)
			(stroke
				(width 0)
				(type default)
			)
			(fill no)
			(layer "F.Fab")
		)
		(pad "1" smd custom
			(at 0 -0.762 90)
			(size 0.2159 0.2159)
			(layers "F.Cu" "F.Mask" "F.Paste")
			(net "P3V3_STBY")
			(options
				(clearance outline)
				(anchor circle)
			)
			(primitives
				(gr_poly
					(pts
						(arc
							(start -0.3302 -0.4318)
							(mid -0.402042 -0.402042)
							(end -0.4318 -0.3302)
						)
						(arc
							(start -0.4318 0.3302)
							(mid -0.402042 0.402042)
							(end -0.3302 0.4318)
						)
						(arc
							(start 0.3302 0.4318)
							(mid 0.402042 0.402042)
							(end 0.4318 0.3302)
						)
						(arc
							(start 0.4318 -0.3302)
							(mid 0.402042 -0.402042)
							(end 0.3302 -0.4318)
						)
					)
					(width 0)
					(fill yes)
				)
			)
		)
		(pad "2" smd custom
			(at 0 0.762 90)
			(size 0.2159 0.2159)
			(layers "F.Cu" "F.Mask" "F.Paste")
			(net "P3V3_STBY_VFB_R")
			(options
				(clearance outline)
				(anchor circle)
			)
			(primitives
				(gr_poly
					(pts
						(arc
							(start -0.3302 -0.4318)
							(mid -0.402042 -0.402042)
							(end -0.4318 -0.3302)
						)
						(arc
							(start -0.4318 0.3302)
							(mid -0.402042 0.402042)
							(end -0.3302 0.4318)
						)
						(arc
							(start 0.3302 0.4318)
							(mid 0.402042 0.402042)
							(end 0.4318 0.3302)
						)
						(arc
							(start 0.4318 -0.3302)
							(mid 0.402042 -0.402042)
							(end 0.3302 -0.4318)
						)
					)
					(width 0)
					(fill yes)
				)
			)
		)
	)
	(footprint ""
		(layer "F.Cu")
		(at 66.715386 -109.265212 -90)
		(property "Reference" "PR166"
			(at 0 0 270)
			(layer "F.SilkS")
			(hide yes)
			(effects
				(font
					(size 1.27 1.27)
				)
			)
		)
		(property "Value" "4K02R2F-GP"
			(at 0.064008 -3.993896 270)
			(unlocked yes)
			(layer "F.Fab")
			(hide yes)
			(effects
				(font
					(size 1.016 1.016)
					(thickness 0.1524)
				)
			)
		)
		(property "Device Type" "R402H16"
			(at 0.064008 -5.517896 270)
			(unlocked yes)
			(layer "F.Fab")
			(hide yes)
			(effects
				(font
					(size 1.016 1.016)
					(thickness 0.1524)
				)
			)
		)
		(duplicate_pad_numbers_are_jumpers no)
		(fp_line
			(start -0.508 -0.9398)
			(end -0.508 0.9398)
			(stroke
				(width 0.1524)
				(type default)
			)
			(layer "F.SilkS")
		)
		(fp_line
			(start 0.508 -0.9398)
			(end -0.508 -0.9398)
			(stroke
				(width 0.1524)
				(type default)
			)
			(layer "F.SilkS")
		)
		(fp_rect
			(start -0.508 0.9398)
			(end 0.508 -0.9398)
			(stroke
				(width 0)
				(type default)
			)
			(fill no)
			(layer "F.CrtYd")
		)
		(fp_rect
			(start -0.508 0.9398)
			(end 0.508 -0.9398)
			(stroke
				(width 0)
				(type default)
			)
			(fill no)
			(layer "F.Fab")
		)
		(pad "1" smd custom
			(at 0 -0.4445 270)
			(size 0.1397 0.1397)
			(layers "F.Cu" "F.Mask" "F.Paste")
			(net "P1V8_EN_S")
			(options
				(clearance outline)
				(anchor circle)
			)
			(primitives
				(gr_poly
					(pts
						(arc
							(start -0.1778 -0.2794)
							(mid -0.249642 -0.249642)
							(end -0.2794 -0.1778)
						)
						(arc
							(start -0.2794 0.1778)
							(mid -0.249642 0.249642)
							(end -0.1778 0.2794)
						)
						(arc
							(start 0.1778 0.2794)
							(mid 0.249642 0.249642)
							(end 0.2794 0.1778)
						)
						(arc
							(start 0.2794 -0.1778)
							(mid 0.249642 -0.249642)
							(end 0.1778 -0.2794)
						)
					)
					(width 0)
					(fill yes)
				)
			)
		)
		(pad "2" smd custom
			(at 0 0.4445 270)
			(size 0.1397 0.1397)
			(layers "F.Cu" "F.Mask" "F.Paste")
			(net "P3V3_STBY")
			(options
				(clearance outline)
				(anchor circle)
			)
			(primitives
				(gr_poly
					(pts
						(arc
							(start -0.1778 -0.2794)
							(mid -0.249642 -0.249642)
							(end -0.2794 -0.1778)
						)
						(arc
							(start -0.2794 0.1778)
							(mid -0.249642 0.249642)
							(end -0.1778 0.2794)
						)
						(arc
							(start 0.1778 0.2794)
							(mid 0.249642 0.249642)
							(end 0.2794 0.1778)
						)
						(arc
							(start 0.2794 -0.1778)
							(mid 0.249642 -0.249642)
							(end 0.1778 -0.2794)
						)
					)
					(width 0)
					(fill yes)
				)
			)
		)
	)
	(footprint ""
		(layer "F.Cu")
		(at 270.764 -186.309 -90)
		(property "Reference" "R607"
			(at 0 0 270)
			(layer "F.SilkS")
			(hide yes)
			(effects
				(font
					(size 1.27 1.27)
				)
			)
		)
		(property "Value" "0R2J-2-GP"
			(at 0.064008 -3.993896 270)
			(unlocked yes)
			(layer "F.Fab")
			(hide yes)
			(effects
				(font
					(size 1.016 1.016)
					(thickness 0.1524)
				)
			)
		)
		(property "Device Type" "R402H16"
			(at 0.064008 -5.517896 270)
			(unlocked yes)
			(layer "F.Fab")
			(hide yes)
			(effects
				(font
					(size 1.016 1.016)
					(thickness 0.1524)
				)
			)
		)
		(duplicate_pad_numbers_are_jumpers no)
		(fp_line
			(start -0.508 -0.9398)
			(end -0.508 0.9398)
			(stroke
				(width 0.1524)
				(type default)
			)
			(layer "F.SilkS")
		)
		(fp_line
			(start 0.508 -0.9398)
			(end -0.508 -0.9398)
			(stroke
				(width 0.1524)
				(type default)
			)
			(layer "F.SilkS")
		)
		(fp_rect
			(start -0.508 0.9398)
			(end 0.508 -0.9398)
			(stroke
				(width 0)
				(type default)
			)
			(fill no)
			(layer "F.CrtYd")
		)
		(fp_rect
			(start -0.508 0.9398)
			(end 0.508 -0.9398)
			(stroke
				(width 0)
				(type default)
			)
			(fill no)
			(layer "F.Fab")
		)
		(pad "1" smd custom
			(at 0 -0.4445 270)
			(size 0.1397 0.1397)
			(layers "F.Cu" "F.Mask" "F.Paste")
			(net "DP_RST_N_R")
			(options
				(clearance outline)
				(anchor circle)
			)
			(primitives
				(gr_poly
					(pts
						(arc
							(start -0.1778 -0.2794)
							(mid -0.249642 -0.249642)
							(end -0.2794 -0.1778)
						)
						(arc
							(start -0.2794 0.1778)
							(mid -0.249642 0.249642)
							(end -0.1778 0.2794)
						)
						(arc
							(start 0.1778 0.2794)
							(mid 0.249642 0.249642)
							(end 0.2794 0.1778)
						)
						(arc
							(start 0.2794 -0.1778)
							(mid 0.249642 -0.249642)
							(end 0.1778 -0.2794)
						)
					)
					(width 0)
					(fill yes)
				)
			)
		)
		(pad "2" smd custom
			(at 0 0.4445 270)
			(size 0.1397 0.1397)
			(layers "F.Cu" "F.Mask" "F.Paste")
			(net "DP_RST_N")
			(options
				(clearance outline)
				(anchor circle)
			)
			(primitives
				(gr_poly
					(pts
						(arc
							(start -0.1778 -0.2794)
							(mid -0.249642 -0.249642)
							(end -0.2794 -0.1778)
						)
						(arc
							(start -0.2794 0.1778)
							(mid -0.249642 0.249642)
							(end -0.1778 0.2794)
						)
						(arc
							(start 0.1778 0.2794)
							(mid 0.249642 0.249642)
							(end 0.2794 0.1778)
						)
						(arc
							(start 0.2794 -0.1778)
							(mid 0.249642 -0.249642)
							(end 0.1778 -0.2794)
						)
					)
					(width 0)
					(fill yes)
				)
			)
		)
	)
)
